# S9S_MB_2U (Grand Teton) — schematic netlist excerpt (pin names and nets, part order shuffled) for the footprints in the layout excerpt that follows; sources: Cadence DE-HDL packaged netlist, KiCad conversion of 03242023_DA0F0TMBIJ0_F0T_Motherboard_J_brd_V01_OCP.brd

H17  HOLE  EMPTY  pkg TH  page 311 : \1\ = NC
R4668  Q_RES  10K 1% EMPTY  pkg 0402LF  page 306 : A = A_HSC_LOW ; B = GND
C1275  Q_CAP  0.1UF 25V 10% X7R  pkg 0402  page 155 : A = P3V3_AUX ; B = GND

(kicad_pcb
	(version 20260206)
	(generator "pcbnew")
	(generator_version "10.0")
	(general
		(thickness 1.6)
		(legacy_teardrops no)
	)
	(paper "A4")
	(title_block
		(title "03242023_DA0F0TMBIJ0_F0T_Motherboard_J_brd_V01_OCP.brd")
		(comment 1 "Grand Teton / footprints 4047-4049 of 6105")
	)
	(layers
		(0 "F.Cu" signal "TOP")
		(4 "In1.Cu" signal "GND")
		(6 "In2.Cu" signal "IN1")
		(8 "In3.Cu" signal "GND1")
		(10 "In4.Cu" signal "IN2")
		(12 "In5.Cu" signal "GND2")
		(14 "In6.Cu" signal "IN3")
		(16 "In7.Cu" signal "GND3")
		(18 "In8.Cu" signal "VCC")
		(20 "In9.Cu" signal "VCC1")
		(22 "In10.Cu" signal "GND4")
		(24 "In11.Cu" signal "IN4")
		(26 "In12.Cu" signal "GND5")
		(28 "In13.Cu" signal "IN5")
		(30 "In14.Cu" signal "GND6")
		(32 "In15.Cu" signal "IN6")
		(34 "In16.Cu" signal "GND7")
		(2 "B.Cu" signal "BOTTOM")
		(9 "F.Adhes" user "F.Adhesive")
		(11 "B.Adhes" user "B.Adhesive")
		(13 "F.Paste" user "Package Geometry/Pastemask Top")
		(15 "B.Paste" user "Package Geometry/Pastemask Bottom")
		(5 "F.SilkS" user "Ref Des/Silkscreen Top")
		(7 "B.SilkS" user "Ref Des/Silkscreen Bottom")
		(1 "F.Mask" user "Board Geometry/Soldermask Top")
		(3 "B.Mask" user "Board Geometry/Soldermask Bottom")
		(17 "Dwgs.User" user "User.Drawings")
		(19 "Cmts.User" user "User.Comments")
		(21 "Eco1.User" user "User.Eco1")
		(23 "Eco2.User" user "User.Eco2")
		(25 "Edge.Cuts" user "Board Geometry/Outline")
		(27 "Margin" user)
		(31 "F.CrtYd" user "Package Geometry/Place Bound Top")
		(29 "B.CrtYd" user "Package Geometry/Place Bound Bottom")
		(35 "F.Fab" user "Ref Des/Assembly Top")
		(33 "B.Fab" user "Ref Des/Assembly Bottom")
	)
	(footprint ""
		(layer "F.Cu")
		(at 381.360172 -297.514772)
		(property "Reference" "H17"
			(at -1.122172 -5.826506 0)
			(unlocked yes)
			(layer "F.SilkS")
			(effects
				(font
					(size 0.7874 0.5842)
					(thickness 0.1524)
				)
				(justify left)
			)
		)
		(property "Value" ""
			(at 0 0 0)
			(layer "F.Fab")
			(effects
				(font
					(size 1.27 1.27)
				)
			)
		)
		(duplicate_pad_numbers_are_jumpers no)
		(fp_circle
			(center 0 0)
			(end 2.5273 0)
			(stroke
				(width 0.1524)
				(type default)
			)
			(fill no)
			(layer "F.SilkS")
		)
		(fp_circle
			(center 0 0)
			(end 2.5273 0)
			(stroke
				(width 0.1524)
				(type default)
			)
			(fill no)
			(layer "B.SilkS")
		)
		(fp_circle
			(center 0 0)
			(end 2.5273 0)
			(stroke
				(width 0.1)
				(type default)
			)
			(fill no)
			(layer "B.Fab")
		)
		(fp_circle
			(center 0 0)
			(end 2.5273 0)
			(stroke
				(width 0.1)
				(type default)
			)
			(fill no)
			(layer "F.Fab")
		)
		(pad "" np_thru_hole circle
			(at 0 0)
			(size 3.429 3.429)
			(drill 3.429)
			(layers "*.Cu" "*.Mask")
			(clearance 0.381)
			(thermal_gap 0.381)
		)
	)
	(footprint ""
		(layer "F.Cu")
		(at 279.262078 -417.2839 -90)
		(property "Reference" "R4668"
			(at 0 0 270)
			(layer "F.SilkS")
			(hide yes)
			(effects
				(font
					(size 1.27 1.27)
				)
			)
		)
		(property "Value" ""
			(at 0 0 270)
			(layer "F.Fab")
			(effects
				(font
					(size 1.27 1.27)
				)
			)
		)
		(duplicate_pad_numbers_are_jumpers no)
		(fp_line
			(start -0.7874 0.4064)
			(end -0.7874 -0.4064)
			(stroke
				(width 0.1524)
				(type default)
			)
			(layer "F.SilkS")
		)
		(fp_line
			(start 0.7874 0.4064)
			(end -0.7874 0.4064)
			(stroke
				(width 0.1524)
				(type default)
			)
			(layer "F.SilkS")
		)
		(fp_line
			(start -0.7874 -0.4064)
			(end 0.7874 -0.4064)
			(stroke
				(width 0.1524)
				(type default)
			)
			(layer "F.SilkS")
		)
		(fp_line
			(start 0.7874 -0.4064)
			(end 0.7874 0.4064)
			(stroke
				(width 0.1524)
				(type default)
			)
			(layer "F.SilkS")
		)
		(fp_line
			(start -0.67945 0.3048)
			(end -0.67945 -0.305054)
			(stroke
				(width 0.1)
				(type default)
			)
			(layer "F.Fab")
		)
		(fp_line
			(start -0.12065 0.3048)
			(end -0.67945 0.3048)
			(stroke
				(width 0.1)
				(type default)
			)
			(layer "F.Fab")
		)
		(fp_line
			(start 0.120396 0.3048)
			(end 0.120396 0.2794)
			(stroke
				(width 0.1)
				(type default)
			)
			(layer "F.Fab")
		)
		(fp_line
			(start 0.67945 0.3048)
			(end 0.120396 0.3048)
			(stroke
				(width 0.1)
				(type default)
			)
			(layer "F.Fab")
		)
		(fp_line
			(start -0.12065 0.2794)
			(end -0.12065 0.3048)
			(stroke
				(width 0.1)
				(type default)
			)
			(layer "F.Fab")
		)
		(fp_line
			(start 0.120396 0.2794)
			(end -0.12065 0.2794)
			(stroke
				(width 0.1)
				(type default)
			)
			(layer "F.Fab")
		)
		(fp_line
			(start -0.12065 -0.2794)
			(end 0.12065 -0.2794)
			(stroke
				(width 0.1)
				(type default)
			)
			(layer "F.Fab")
		)
		(fp_line
			(start 0.12065 -0.2794)
			(end 0.12065 -0.3048)
			(stroke
				(width 0.1)
				(type default)
			)
			(layer "F.Fab")
		)
		(fp_line
			(start 0.12065 -0.3048)
			(end 0.67945 -0.3048)
			(stroke
				(width 0.1)
				(type default)
			)
			(layer "F.Fab")
		)
		(fp_line
			(start 0.67945 -0.3048)
			(end 0.67945 0.3048)
			(stroke
				(width 0.1)
				(type default)
			)
			(layer "F.Fab")
		)
		(fp_line
			(start -0.67945 -0.305054)
			(end -0.12065 -0.305054)
			(stroke
				(width 0.1)
				(type default)
			)
			(layer "F.Fab")
		)
		(fp_line
			(start -0.12065 -0.305054)
			(end -0.12065 -0.2794)
			(stroke
				(width 0.1)
				(type default)
			)
			(layer "F.Fab")
		)
		(pad "1" smd circle
			(at -0.40005 0 270)
			(size 0 0)
			(layers "F.Cu" "F.Mask" "F.Paste")
			(net "A_HSC_LOW")
		)
		(pad "2" smd circle
			(at 0.40005 0 270)
			(size 0 0)
			(layers "F.Cu" "F.Mask" "F.Paste")
			(net "GND")
		)
	)
	(footprint ""
		(layer "F.Cu")
		(at 211.572094 -14.892528)
		(property "Reference" "C1275"
			(at 0 0 0)
			(layer "F.SilkS")
			(hide yes)
			(effects
				(font
					(size 1.27 1.27)
				)
			)
		)
		(property "Value" ""
			(at 0 0 0)
			(layer "F.Fab")
			(effects
				(font
					(size 1.27 1.27)
				)
			)
		)
		(duplicate_pad_numbers_are_jumpers no)
		(fp_line
			(start -0.7874 -0.4064)
			(end 0.7874 -0.4064)
			(stroke
				(width 0.1524)
				(type default)
			)
			(layer "F.SilkS")
		)
		(fp_line
			(start -0.7874 0.4064)
			(end -0.7874 -0.4064)
			(stroke
				(width 0.1524)
				(type default)
			)
			(layer "F.SilkS")
		)
		(fp_line
			(start 0.7874 -0.4064)
			(end 0.7874 0.4064)
			(stroke
				(width 0.1524)
				(type default)
			)
			(layer "F.SilkS")
		)
		(fp_line
			(start 0.7874 0.4064)
			(end -0.7874 0.4064)
			(stroke
				(width 0.1524)
				(type default)
			)
			(layer "F.SilkS")
		)
		(fp_line
			(start -0.67945 -0.305054)
			(end -0.12065 -0.305054)
			(stroke
				(width 0.1)
				(type default)
			)
			(layer "F.Fab")
		)
		(fp_line
			(start -0.67945 0.3048)
			(end -0.67945 -0.305054)
			(stroke
				(width 0.1)
				(type default)
			)
			(layer "F.Fab")
		)
		(fp_line
			(start -0.12065 -0.305054)
			(end -0.12065 -0.2794)
			(stroke
				(width 0.1)
				(type default)
			)
			(layer "F.Fab")
		)
		(fp_line
			(start -0.12065 -0.2794)
			(end 0.12065 -0.2794)
			(stroke
				(width 0.1)
				(type default)
			)
			(layer "F.Fab")
		)
		(fp_line
			(start -0.12065 0.2794)
			(end -0.12065 0.3048)
			(stroke
				(width 0.1)
				(type default)
			)
			(layer "F.Fab")
		)
		(fp_line
			(start -0.12065 0.3048)
			(end -0.67945 0.3048)
			(stroke
				(width 0.1)
				(type default)
			)
			(layer "F.Fab")
		)
		(fp_line
			(start 0.120396 0.2794)
			(end -0.12065 0.2794)
			(stroke
				(width 0.1)
				(type default)
			)
			(layer "F.Fab")
		)
		(fp_line
			(start 0.120396 0.3048)
			(end 0.120396 0.2794)
			(stroke
				(width 0.1)
				(type default)
			)
			(layer "F.Fab")
		)
		(fp_line
			(start 0.12065 -0.3048)
			(end 0.67945 -0.3048)
			(stroke
				(width 0.1)
				(type default)
			)
			(layer "F.Fab")
		)
		(fp_line
			(start 0.12065 -0.2794)
			(end 0.12065 -0.3048)
			(stroke
				(width 0.1)
				(type default)
			)
			(layer "F.Fab")
		)
		(fp_line
			(start 0.67945 -0.3048)
			(end 0.67945 0.3048)
			(stroke
				(width 0.1)
				(type default)
			)
			(layer "F.Fab")
		)
		(fp_line
			(start 0.67945 0.3048)
			(end 0.120396 0.3048)
			(stroke
				(width 0.1)
				(type default)
			)
			(layer "F.Fab")
		)
		(pad "1" smd circle
			(at -0.40005 0)
			(size 0 0)
			(layers "F.Cu" "F.Mask" "F.Paste")
			(net "P3V3_AUX")
		)
		(pad "2" smd circle
			(at 0.40005 0)
			(size 0 0)
			(layers "F.Cu" "F.Mask" "F.Paste")
			(net "GND")
		)
	)
)
